# S9S_MB_2U (Grand Teton) — schematic netlist excerpt (pin names and nets, part order shuffled) for the footprints in the layout excerpt that follows; sources: Cadence DE-HDL packaged netlist, KiCad conversion of 03242023_DA0F0TMBIJ0_F0T_Motherboard_J_brd_V01_OCP.brd

X22  TP_TDR_4P_FTS  TP_TDR_4P_DIP EMPTY  pkg TH  page 309
  S1  = TDR_DIFF_100_IN3_DN
  P1  = T1_GND
  P2  = T1_GND
  S2  = TDR_DIFF_100_IN3_DP

C1754  Q_CAP  1000PF 50V 5% EMPTY  pkg 0402  page 148 : A = FM_SWB_BIC_READY_ISO_N ; B = GND

(kicad_pcb
	(version 20260206)
	(generator "pcbnew")
	(generator_version "10.0")
	(general
		(thickness 1.6)
		(legacy_teardrops no)
	)
	(paper "A4")
	(title_block
		(title "03242023_DA0F0TMBIJ0_F0T_Motherboard_J_brd_V01_OCP.brd")
		(comment 1 "Grand Teton / footprints 1174-1175 of 6105")
	)
	(layers
		(0 "F.Cu" signal "TOP")
		(4 "In1.Cu" signal "GND")
		(6 "In2.Cu" signal "IN1")
		(8 "In3.Cu" signal "GND1")
		(10 "In4.Cu" signal "IN2")
		(12 "In5.Cu" signal "GND2")
		(14 "In6.Cu" signal "IN3")
		(16 "In7.Cu" signal "GND3")
		(18 "In8.Cu" signal "VCC")
		(20 "In9.Cu" signal "VCC1")
		(22 "In10.Cu" signal "GND4")
		(24 "In11.Cu" signal "IN4")
		(26 "In12.Cu" signal "GND5")
		(28 "In13.Cu" signal "IN5")
		(30 "In14.Cu" signal "GND6")
		(32 "In15.Cu" signal "IN6")
		(34 "In16.Cu" signal "GND7")
		(2 "B.Cu" signal "BOTTOM")
		(9 "F.Adhes" user "F.Adhesive")
		(11 "B.Adhes" user "B.Adhesive")
		(13 "F.Paste" user "Package Geometry/Pastemask Top")
		(15 "B.Paste" user "Package Geometry/Pastemask Bottom")
		(5 "F.SilkS" user "Ref Des/Silkscreen Top")
		(7 "B.SilkS" user "Ref Des/Silkscreen Bottom")
		(1 "F.Mask" user "Board Geometry/Soldermask Top")
		(3 "B.Mask" user "Board Geometry/Soldermask Bottom")
		(17 "Dwgs.User" user "User.Drawings")
		(19 "Cmts.User" user "User.Comments")
		(21 "Eco1.User" user "User.Eco1")
		(23 "Eco2.User" user "User.Eco2")
		(25 "Edge.Cuts" user "Board Geometry/Outline")
		(27 "Margin" user)
		(31 "F.CrtYd" user "Package Geometry/Place Bound Top")
		(29 "B.CrtYd" user "Package Geometry/Place Bound Bottom")
		(35 "F.Fab" user "Ref Des/Assembly Top")
		(33 "B.Fab" user "Ref Des/Assembly Bottom")
	)
	(footprint ""
		(layer "F.Cu")
		(at 488.03433 -148.048472 90)
		(property "Reference" "X22"
			(at -3.517392 3.52298 90)
			(unlocked yes)
			(layer "F.SilkS")
			(effects
				(font
					(size 0.7874 0.5842)
					(thickness 0.1524)
				)
				(justify left)
			)
		)
		(property "Value" ""
			(at 0 0 90)
			(layer "F.Fab")
			(effects
				(font
					(size 1.27 1.27)
				)
			)
		)
		(property "Device Type" "TP_TDR_4P_FTS_TH-TP_TDR_4P_DIPA"
			(at 1.30175 1.27 180)
			(unlocked yes)
			(layer "F.Fab")
			(hide yes)
			(effects
				(font
					(size 0.635 0.4064)
					(thickness 0.1524)
				)
			)
		)
		(property "User Part Number" "N_A"
			(at 1.30175 1.27 180)
			(unlocked yes)
			(layer "Cmts.User")
			(hide yes)
			(effects
				(font
					(size 0.635 0.4064)
					(thickness 0.1524)
				)
			)
		)
		(duplicate_pad_numbers_are_jumpers no)
		(fp_line
			(start 2.54 -1.27)
			(end 0 -1.27)
			(stroke
				(width 0.1524)
				(type default)
			)
			(layer "F.SilkS")
		)
		(fp_line
			(start 0 -1.27)
			(end 0 -0.635)
			(stroke
				(width 0.1524)
				(type default)
			)
			(layer "F.SilkS")
		)
		(fp_line
			(start 2.54 -1.1303)
			(end 2.54 -1.27)
			(stroke
				(width 0.1524)
				(type default)
			)
			(layer "F.SilkS")
		)
		(fp_line
			(start 0 0.635)
			(end 0 1.905)
			(stroke
				(width 0.1524)
				(type default)
			)
			(layer "F.SilkS")
		)
		(fp_line
			(start 2.54 1.4097)
			(end 2.54 1.1303)
			(stroke
				(width 0.1524)
				(type default)
			)
			(layer "F.SilkS")
		)
		(fp_line
			(start 0 3.175)
			(end 0 3.81)
			(stroke
				(width 0.1524)
				(type default)
			)
			(layer "F.SilkS")
		)
		(fp_line
			(start 2.54 3.81)
			(end 2.54 3.6703)
			(stroke
				(width 0.1524)
				(type default)
			)
			(layer "F.SilkS")
		)
		(fp_line
			(start 0 3.81)
			(end 2.54 3.81)
			(stroke
				(width 0.1524)
				(type default)
			)
			(layer "F.SilkS")
		)
		(fp_poly
			(pts
				(xy -0.761746 0) (xy -2.285746 0.762) (xy -2.285746 -0.762)
			)
			(stroke
				(width 0)
				(type default)
			)
			(fill yes)
			(layer "F.SilkS")
		)
		(fp_line
			(start 2.54 -1.27)
			(end 0 -1.27)
			(stroke
				(width 0.1)
				(type default)
			)
			(layer "F.Fab")
		)
		(fp_line
			(start 0 -1.27)
			(end 0 3.81)
			(stroke
				(width 0.1)
				(type default)
			)
			(layer "F.Fab")
		)
		(fp_line
			(start 2.54 3.81)
			(end 2.54 -1.27)
			(stroke
				(width 0.1)
				(type default)
			)
			(layer "F.Fab")
		)
		(fp_line
			(start 0 3.81)
			(end 2.54 3.81)
			(stroke
				(width 0.1)
				(type default)
			)
			(layer "F.Fab")
		)
		(fp_poly
			(pts
				(xy -0.761746 0) (xy -2.285746 -0.762) (xy -2.285746 0.762)
			)
			(stroke
				(width 0)
				(type default)
			)
			(fill yes)
			(layer "F.Fab")
		)
		(pad "1" thru_hole circle
			(at 0 0 90)
			(size 1.0033 1.0033)
			(drill 0.249936)
			(layers "*.Cu" "*.Mask")
			(remove_unused_layers no)
			(net "TDR_DIFF_100_IN3_DN")
			(clearance 0.10795)
			(thermal_gap 0.10795)
			(padstack
				(mode front_inner_back)
				(layer "Inner"
					(shape circle)
					(size 0.8001 0.8001)
					(clearance 0.1524)
				)
				(layer "B.Cu"
					(shape circle)
					(size 1.0033 1.0033)
					(clearance 0.10795)
				)
			)
		)
		(pad "2" thru_hole circle
			(at 2.54 0 90)
			(size 1.9939 1.9939)
			(drill 0.249936)
			(layers "*.Cu" "*.Mask")
			(remove_unused_layers no)
			(net "T1_GND")
			(clearance 0.10795)
			(thermal_gap 0.10795)
			(padstack
				(mode front_inner_back)
				(layer "Inner"
					(shape circle)
					(size 0.8001 0.8001)
					(clearance 0.1524)
				)
				(layer "B.Cu"
					(shape circle)
					(size 1.9939 1.9939)
					(clearance 0.10795)
				)
			)
		)
		(pad "3" thru_hole circle
			(at 2.54 2.54 90)
			(size 1.9939 1.9939)
			(drill 0.249936)
			(layers "*.Cu" "*.Mask")
			(remove_unused_layers no)
			(net "T1_GND")
			(clearance 0.10795)
			(thermal_gap 0.10795)
			(padstack
				(mode front_inner_back)
				(layer "Inner"
					(shape circle)
					(size 0.8001 0.8001)
					(clearance 0.1524)
				)
				(layer "B.Cu"
					(shape circle)
					(size 1.9939 1.9939)
					(clearance 0.10795)
				)
			)
		)
		(pad "4" thru_hole circle
			(at 0 2.54 90)
			(size 1.0033 1.0033)
			(drill 0.249936)
			(layers "*.Cu" "*.Mask")
			(remove_unused_layers no)
			(net "TDR_DIFF_100_IN3_DP")
			(clearance 0.10795)
			(thermal_gap 0.10795)
			(padstack
				(mode front_inner_back)
				(layer "Inner"
					(shape circle)
					(size 0.8001 0.8001)
					(clearance 0.1524)
				)
				(layer "B.Cu"
					(shape circle)
					(size 1.0033 1.0033)
					(clearance 0.10795)
				)
			)
		)
	)
	(footprint ""
		(layer "F.Cu")
		(at 424.204892 -390.616948 180)
		(property "Reference" "C1754"
			(at 0 0 180)
			(layer "F.SilkS")
			(hide yes)
			(effects
				(font
					(size 1.27 1.27)
				)
			)
		)
		(property "Value" ""
			(at 0 0 180)
			(layer "F.Fab")
			(effects
				(font
					(size 1.27 1.27)
				)
			)
		)
		(duplicate_pad_numbers_are_jumpers no)
		(fp_line
			(start 0.7874 0.4064)
			(end -0.7874 0.4064)
			(stroke
				(width 0.1524)
				(type default)
			)
			(layer "F.SilkS")
		)
		(fp_line
			(start 0.7874 -0.4064)
			(end 0.7874 0.4064)
			(stroke
				(width 0.1524)
				(type default)
			)
			(layer "F.SilkS")
		)
		(fp_line
			(start -0.7874 0.4064)
			(end -0.7874 -0.4064)
			(stroke
				(width 0.1524)
				(type default)
			)
			(layer "F.SilkS")
		)
		(fp_line
			(start -0.7874 -0.4064)
			(end 0.7874 -0.4064)
			(stroke
				(width 0.1524)
				(type default)
			)
			(layer "F.SilkS")
		)
		(fp_line
			(start 0.67945 0.3048)
			(end 0.120396 0.3048)
			(stroke
				(width 0.1)
				(type default)
			)
			(layer "F.Fab")
		)
		(fp_line
			(start 0.67945 -0.3048)
			(end 0.67945 0.3048)
			(stroke
				(width 0.1)
				(type default)
			)
			(layer "F.Fab")
		)
		(fp_line
			(start 0.12065 -0.2794)
			(end 0.12065 -0.3048)
			(stroke
				(width 0.1)
				(type default)
			)
			(layer "F.Fab")
		)
		(fp_line
			(start 0.12065 -0.3048)
			(end 0.67945 -0.3048)
			(stroke
				(width 0.1)
				(type default)
			)
			(layer "F.Fab")
		)
		(fp_line
			(start 0.120396 0.3048)
			(end 0.120396 0.2794)
			(stroke
				(width 0.1)
				(type default)
			)
			(layer "F.Fab")
		)
		(fp_line
			(start 0.120396 0.2794)
			(end -0.12065 0.2794)
			(stroke
				(width 0.1)
				(type default)
			)
			(layer "F.Fab")
		)
		(fp_line
			(start -0.12065 0.3048)
			(end -0.67945 0.3048)
			(stroke
				(width 0.1)
				(type default)
			)
			(layer "F.Fab")
		)
		(fp_line
			(start -0.12065 0.2794)
			(end -0.12065 0.3048)
			(stroke
				(width 0.1)
				(type default)
			)
			(layer "F.Fab")
		)
		(fp_line
			(start -0.12065 -0.2794)
			(end 0.12065 -0.2794)
			(stroke
				(width 0.1)
				(type default)
			)
			(layer "F.Fab")
		)
		(fp_line
			(start -0.12065 -0.305054)
			(end -0.12065 -0.2794)
			(stroke
				(width 0.1)
				(type default)
			)
			(layer "F.Fab")
		)
		(fp_line
			(start -0.67945 0.3048)
			(end -0.67945 -0.305054)
			(stroke
				(width 0.1)
				(type default)
			)
			(layer "F.Fab")
		)
		(fp_line
			(start -0.67945 -0.305054)
			(end -0.12065 -0.305054)
			(stroke
				(width 0.1)
				(type default)
			)
			(layer "F.Fab")
		)
		(pad "1" smd circle
			(at -0.40005 0 180)
			(size 0 0)
			(layers "F.Cu" "F.Mask" "F.Paste")
			(net "FM_SWB_BIC_READY_ISO_N")
		)
		(pad "2" smd circle
			(at 0.40005 0 180)
			(size 0 0)
			(layers "F.Cu" "F.Mask" "F.Paste")
			(net "GND")
		)
	)
)
